FILE_TYPE = MULTI_PHYS_TABLE;

PART 'GTL2014PW'

{========================================================================================}
:VALUE       | PART_TYPE | MATERIAL | PART_NUMBER    = STANDARD        | LIFECYCLE      | PART_NUMBER   | JEDEC_TYPE | DESCRIPTION                      | MANUFTR | MANUF_PN    | RD_CMPLS_LVL | CMPLS_LVL | FROM_PJ      | CLASS | DIP_SMD | DATA              | EE_CHECK_LIST | FP_ECN | PSL | CREATOR | STATUS | CREATEDAY  ;
{========================================================================================}
 'GTL2014PW' | 'SMLF'    | 'IC'     | 'AL002014K01'(!) = ''               | ''               | 'AL002014K01' |'TSSOP14'| 'IC OTHER(14P) GTL2014PW(TSSOP)' | 'NXP'   | 'GTL2014PW' | 'EP(V1)'     | 'EP(V1)'  | 'S2B-YU-LIN' | 'IC'  | ''      | 'NXP_GTL2014.pdf' | ''            | ''     | ''  | ''      | ''     | '20120731'
 'GTL2014PW' | 'SMLF'    | 'EMPTY'  | 'AL002014K01'(!) = ''               | ''               | 'AL002014K01' |'TSSOP14'| 'IC OTHER(14P) GTL2014PW(TSSOP)' | 'NXP'   | 'GTL2014PW' | 'EP(V1)'     | 'EP(V1)'  | 'S2B-YU-LIN' | 'IC'  | ''      | 'NXP_GTL2014.pdf' | ''            | ''     | ''  | ''      | ''     | '20120731'

END_PART

END.

